(kicad_sch (version 20230121) (generator eeschema)

  (paper "A3")

  (title_block
    (title "Kria K26 Devboard")
    (date "2024-03-26")
    (rev "1.2.5")
    (comment 1 "www.antmicro.com")
    (comment 2 "Antmicro Ltd.")
  )

  (junction (at 167.64 88.9) (diameter 0) (color 0 0 0 0)
  )
  (junction (at 152.4 88.9) (diameter 0) (color 0 0 0 0)
  )

  (no_connect (at 144.78 91.44))

  (wire (pts (xy 152.4 88.9) (xy 167.64 88.9))
    (stroke (width 0) (type default))
  )
  (wire (pts (xy 152.4 93.98) (xy 152.4 88.9))
    (stroke (width 0) (type default))
  )
  (wire (pts (xy 167.64 88.9) (xy 180.594 88.9))
    (stroke (width 0) (type default))
  )
  (wire (pts (xy 144.78 93.98) (xy 146.05 93.98))
    (stroke (width 0) (type default))
  )
  (wire (pts (xy 167.64 88.9) (xy 167.64 87.63))
    (stroke (width 0) (type default))
  )
  (wire (pts (xy 167.64 88.9) (xy 167.64 90.17))
    (stroke (width 0) (type default))
  )
  (wire (pts (xy 152.4 99.06) (xy 152.4 102.87))
    (stroke (width 0) (type default))
  )
  (wire (pts (xy 146.05 93.98) (xy 146.05 102.87))
    (stroke (width 0) (type default))
  )
  (wire (pts (xy 144.78 88.9) (xy 152.4 88.9))
    (stroke (width 0) (type default))
  )

  (text "6-15V" (at 130.81 97.79 0)
    (effects (font (size 1.27 1.27)) (justify left bottom))
  )

  (hierarchical_label "DC_IN" (shape input) (at 180.594 88.9 0) (fields_autoplaced)
    (effects (font (size 1.27 1.27)) (justify left))
  )

  (symbol (lib_id "kria-k26-devboard:SMF4L15CA") (at 167.64 90.17 270) (unit 1)
    (in_bom yes) (on_board yes) (dnp no) (fields_autoplaced)
    (property "Reference" "D27" (at 169.926 95.2499 90)
      (effects (font (size 1.27 1.27)) (justify left))
    )
    (property "Value" "SMF4L15CA" (at 169.926 97.7899 90)
      (effects (font (size 1.27 1.27) (thickness 0.15)) (justify left))
    )
    (property "Footprint" "kria-k26-devboard-footprints:SOD-123FL" (at 167.64 90.17 0)
      (effects (font (size 1.27 1.27) (thickness 0.15)) (justify left bottom) hide)
    )
    (property "Datasheet" "https://www.mouser.pl/datasheet/2/240/Littelfuse_TVS_Diode_SMF4L_Datasheet_pdf-1665786.pdf" (at 167.64 90.17 0)
      (effects (font (size 1.27 1.27) (thickness 0.15)) (justify left bottom) hide)
    )
    (property "MPN" "SMF4L15CA" (at 167.64 90.17 0)
      (effects (font (size 1.27 1.27) (thickness 0.15)) (justify left bottom) hide)
    )
    (property "Manufacturer" "Infineon Technologies" (at 167.64 90.17 0)
      (effects (font (size 1.27 1.27) (thickness 0.15)) (justify left bottom) hide)
    )
    (property "Author" "Antmicro" (at 147.32 116.84 0)
      (effects (font (size 1.27 1.27) (thickness 0.15)) (justify left bottom) hide)
    )
    (property "License" "Apache-2.0" (at 144.78 116.84 0)
      (effects (font (size 1.27 1.27) (thickness 0.15)) (justify left bottom) hide)
    )
    (pin "1")
    (pin "2")
    (instances
      (project "kria-k26-devboard"
        (path ""
          (reference "D27") (unit 1)
        )
      )
    )
  )

  (symbol (lib_id "kria-k26-devboard:BarrelJack_Pin2mm_MJ-179PH") (at 144.78 88.9 0) (unit 1)
    (in_bom yes) (on_board yes) (dnp no) (fields_autoplaced)
    (property "Reference" "J11" (at 137.16 82.55 0)
      (effects (font (size 1.524 1.524)))
    )
    (property "Value" "BarrelJack_Pin2mm_MJ-179PH" (at 152.4 85.09 0)
      (effects (font (size 1.27 1.27) (thickness 0.15)) hide)
    )
    (property "Footprint" "kria-k26-devboard-footprints:BarrelJack_Pin2mm_MJ-179PH" (at 146.05 97.79 0)
      (effects (font (size 1.27 1.27) (thickness 0.15)) (justify left bottom) hide)
    )
    (property "Datasheet" "https://www.farnell.com/datasheets/3167288.pdf" (at 144.78 88.9 0)
      (effects (font (size 1.27 1.27) (thickness 0.15)) (justify left bottom) hide)
    )
    (property "Manufacturer" "Multicomp Pro" (at 145.415 100.965 0)
      (effects (font (size 1.27 1.27) (thickness 0.15)) (justify left bottom) hide)
    )
    (property "MPN" "MJ-179PH" (at 137.16 85.09 0)
      (effects (font (size 1.27 1.27) (thickness 0.15)))
    )
    (property "Author" "Antmicro" (at 162.56 109.22 0)
      (effects (font (size 1.27 1.27) (thickness 0.15)) (justify left bottom) hide)
    )
    (property "License" "Apache-2.0" (at 162.56 111.76 0)
      (effects (font (size 1.27 1.27) (thickness 0.15)) (justify left bottom) hide)
    )
    (pin "1")
    (pin "2")
    (pin "3")
    (instances
      (project "kria-k26-devboard"
        (path ""
          (reference "J11") (unit 1)
        )
      )
    )
  )

  (symbol (lib_id "kria-k26-devboard:GND") (at 146.05 102.87 0) (unit 1)
    (in_bom yes) (on_board yes) (dnp no) (fields_autoplaced)
    (property "Reference" "#PWR0396" (at 146.05 109.22 0)
      (effects (font (size 1.27 1.27)) hide)
    )
    (property "Value" "GND" (at 146.05 107.95 0)
      (effects (font (size 1.27 1.27)))
    )
    (property "Footprint" "" (at 154.94 110.49 0)
      (effects (font (size 1.27 1.27) (thickness 0.15)) (justify left bottom) hide)
    )
    (property "Datasheet" "" (at 154.94 115.57 0)
      (effects (font (size 1.27 1.27) (thickness 0.15)) (justify left bottom) hide)
    )
    (property "Author" "Antmicro" (at 154.94 110.49 0)
      (effects (font (size 1.27 1.27) (thickness 0.15)) (justify left bottom) hide)
    )
    (property "License" "Apache-2.0" (at 154.94 113.03 0)
      (effects (font (size 1.27 1.27) (thickness 0.15)) (justify left bottom) hide)
    )
    (pin "1")
    (instances
      (project "kria-k26-devboard"
        (path ""
          (reference "#PWR0396") (unit 1)
        )
      )
    )
  )

  (symbol (lib_id "kria-k26-devboard:C_100n_50V_0402") (at 152.4 93.98 270) (unit 1)
    (in_bom yes) (on_board yes) (dnp no) (fields_autoplaced)
    (property "Reference" "C232" (at 154.94 95.2562 90)
      (effects (font (size 1.27 1.27)) (justify left))
    )
    (property "Value" "C_100n_50V_0402" (at 152.4 93.98 0)
      (effects (font (size 1.27 1.27) (thickness 0.15)) (justify left bottom) hide)
    )
    (property "Footprint" "kria-k26-devboard-footprints:C_0402_1005Metric" (at 152.4 93.98 0)
      (effects (font (size 1.27 1.27) (thickness 0.15)) (justify left bottom) hide)
    )
    (property "Datasheet" " " (at 152.4 93.98 0)
      (effects (font (size 1.27 1.27) (thickness 0.15)) (justify left bottom) hide)
    )
    (property "MPN" "GRM155R71H104KE14D" (at 152.4 93.98 0)
      (effects (font (size 1.27 1.27) (thickness 0.15)) (justify left bottom) hide)
    )
    (property "Manufacturer" "Murata" (at 152.4 93.98 0)
      (effects (font (size 1.27 1.27) (thickness 0.15)) (justify left bottom) hide)
    )
    (property "Val" "100n/50V" (at 154.94 97.7962 90)
      (effects (font (size 1.27 1.27) (thickness 0.15)) (justify left))
    )
    (property "License" "Apache-2.0" (at 129.54 114.3 0)
      (effects (font (size 1.27 1.27) (thickness 0.15)) (justify left bottom) hide)
    )
    (property "Author" "Antmicro" (at 127 114.3 0)
      (effects (font (size 1.27 1.27) (thickness 0.15)) (justify left bottom) hide)
    )
    (property "Voltage" "" (at 124.46 114.3 0)
      (effects (font (size 1.27 1.27)) (justify left bottom) hide)
    )
    (property "Dielectric" "" (at 121.92 114.3 0)
      (effects (font (size 1.27 1.27)) (justify left bottom) hide)
    )
    (pin "1")
    (pin "2")
    (instances
      (project "kria-k26-devboard"
        (path ""
          (reference "C232") (unit 1)
        )
      )
    )
  )

  (symbol (lib_id "kria-k26-devboard:TP_0.75mm_SMD") (at 167.64 87.63 90) (unit 1)
    (in_bom yes) (on_board yes) (dnp no) (fields_autoplaced)
    (property "Reference" "TP46" (at 170.18 84.4549 90)
      (effects (font (size 1.27 1.27)) (justify right))
    )
    (property "Value" "TP_0.75mm_SMD" (at 170.18 87.63 0)
      (effects (font (size 1.27 1.27) (thickness 0.15)) (justify left bottom) hide)
    )
    (property "Footprint" "kria-k26-devboard-footprints:TP_SMD_0.75mm" (at 162.56 82.55 0)
      (effects (font (size 1.27 1.27) (thickness 0.15)) (justify left bottom) hide)
    )
    (property "Datasheet" "" (at 160.02 82.55 0)
      (effects (font (size 1.27 1.27) (thickness 0.15)) (justify left bottom) hide)
    )
    (property "MPN" "" (at 167.64 87.63 0)
      (effects (font (size 1.27 1.27) (thickness 0.15)) (justify left bottom) hide)
    )
    (property "Manufacturer" "" (at 167.64 87.63 0)
      (effects (font (size 1.27 1.27) (thickness 0.15)) (justify left bottom) hide)
    )
    (property "Author" "Antmicro" (at 182.88 72.39 0)
      (effects (font (size 1.27 1.27) (thickness 0.15)) (justify left bottom) hide)
    )
    (property "License" "Apache-2.0" (at 185.42 72.39 0)
      (effects (font (size 1.27 1.27) (thickness 0.15)) (justify left bottom) hide)
    )
    (pin "1")
    (instances
      (project "kria-k26-devboard"
        (path ""
          (reference "TP46") (unit 1)
        )
      )
    )
  )

  (symbol (lib_id "kria-k26-devboard:GND") (at 167.64 102.87 0) (unit 1)
    (in_bom yes) (on_board yes) (dnp no) (fields_autoplaced)
    (property "Reference" "#PWR0107" (at 167.64 109.22 0)
      (effects (font (size 1.27 1.27)) hide)
    )
    (property "Value" "GND" (at 167.64 107.95 0)
      (effects (font (size 1.27 1.27)))
    )
    (property "Footprint" "" (at 176.53 110.49 0)
      (effects (font (size 1.27 1.27) (thickness 0.15)) (justify left bottom) hide)
    )
    (property "Datasheet" "" (at 176.53 115.57 0)
      (effects (font (size 1.27 1.27) (thickness 0.15)) (justify left bottom) hide)
    )
    (property "Author" "Antmicro" (at 176.53 110.49 0)
      (effects (font (size 1.27 1.27) (thickness 0.15)) (justify left bottom) hide)
    )
    (property "License" "Apache-2.0" (at 176.53 113.03 0)
      (effects (font (size 1.27 1.27) (thickness 0.15)) (justify left bottom) hide)
    )
    (pin "1")
    (instances
      (project "kria-k26-devboard"
        (path ""
          (reference "#PWR0107") (unit 1)
        )
      )
    )
  )

  (symbol (lib_id "kria-k26-devboard:GND") (at 152.4 102.87 0) (unit 1)
    (in_bom yes) (on_board yes) (dnp no) (fields_autoplaced)
    (property "Reference" "#PWR0104" (at 152.4 109.22 0)
      (effects (font (size 1.27 1.27)) hide)
    )
    (property "Value" "GND" (at 152.4 107.95 0)
      (effects (font (size 1.27 1.27)))
    )
    (property "Footprint" "" (at 161.29 110.49 0)
      (effects (font (size 1.27 1.27) (thickness 0.15)) (justify left bottom) hide)
    )
    (property "Datasheet" "" (at 161.29 115.57 0)
      (effects (font (size 1.27 1.27) (thickness 0.15)) (justify left bottom) hide)
    )
    (property "Author" "Antmicro" (at 161.29 110.49 0)
      (effects (font (size 1.27 1.27) (thickness 0.15)) (justify left bottom) hide)
    )
    (property "License" "Apache-2.0" (at 161.29 113.03 0)
      (effects (font (size 1.27 1.27) (thickness 0.15)) (justify left bottom) hide)
    )
    (pin "1")
    (instances
      (project "kria-k26-devboard"
        (path ""
          (reference "#PWR0104") (unit 1)
        )
      )
    )
  )
)
